(kicad_pcb
	(version 20260206)
	(generator "pcbnew")
	(generator_version "10.0")
	(general
		(thickness 1.6)
		(legacy_teardrops no)
	)
	(paper "A4")
	(title_block
		(title "fcb — Lightning_FCB_BRD.brd")
		(comment 1 "Lightning (Wiwynn / Facebook NVMe JBOF) / footprints 263-268 of 495")
	)
	(layers
		(0 "F.Cu" signal "TOP")
		(4 "In1.Cu" signal "L2GND")
		(6 "In2.Cu" signal "L3VCC")
		(2 "B.Cu" signal "BOTTOM")
		(9 "F.Adhes" user "F.Adhesive")
		(11 "B.Adhes" user "B.Adhesive")
		(13 "F.Paste" user "Package Geometry/Pastemask Top")
		(15 "B.Paste" user "Package Geometry/Pastemask Bottom")
		(5 "F.SilkS" user "Ref Des/Silkscreen Top")
		(7 "B.SilkS" user "Ref Des/Silkscreen Bottom")
		(1 "F.Mask" user "Board Geometry/Soldermask Top")
		(3 "B.Mask" user "Board Geometry/Soldermask Bottom")
		(17 "Dwgs.User" user "User.Drawings")
		(19 "Cmts.User" user "User.Comments")
		(21 "Eco1.User" user "User.Eco1")
		(23 "Eco2.User" user "User.Eco2")
		(25 "Edge.Cuts" user "Board Geometry/Outline")
		(27 "Margin" user)
		(31 "F.CrtYd" user "Package Geometry/Place Bound Top")
		(29 "B.CrtYd" user "Package Geometry/Place Bound Bottom")
		(35 "F.Fab" user "Ref Des/Assembly Top")
		(33 "B.Fab" user "Ref Des/Assembly Bottom")
	)
	(footprint ""
		(layer "F.Cu")
		(at 21.766784 -216.6366 90)
		(property "Reference" "R132"
			(at 0 0 90)
			(layer "F.SilkS")
			(hide yes)
			(effects
				(font
					(size 1.27 1.27)
				)
			)
		)
		(property "Value" "4K7R2F-GP"
			(at 0.064008 -3.993896 90)
			(unlocked yes)
			(layer "F.Fab")
			(hide yes)
			(effects
				(font
					(size 1.016 1.016)
					(thickness 0.1524)
				)
			)
		)
		(property "Device Type" "R402H16"
			(at 0.064008 -5.517896 90)
			(unlocked yes)
			(layer "F.Fab")
			(hide yes)
			(effects
				(font
					(size 1.016 1.016)
					(thickness 0.1524)
				)
			)
		)
		(duplicate_pad_numbers_are_jumpers no)
		(fp_line
			(start 0.508 -0.9398)
			(end -0.508 -0.9398)
			(stroke
				(width 0.1524)
				(type default)
			)
			(layer "F.SilkS")
		)
		(fp_line
			(start -0.508 -0.9398)
			(end -0.508 0.9398)
			(stroke
				(width 0.1524)
				(type default)
			)
			(layer "F.SilkS")
		)
		(fp_rect
			(start -0.508 0.9398)
			(end 0.508 -0.9398)
			(stroke
				(width 0)
				(type default)
			)
			(fill no)
			(layer "F.CrtYd")
		)
		(fp_rect
			(start -0.508 0.9398)
			(end 0.508 -0.9398)
			(stroke
				(width 0)
				(type default)
			)
			(fill no)
			(layer "F.Fab")
		)
		(pad "1" smd custom
			(at 0 -0.4445 90)
			(size 0.1397 0.1397)
			(layers "F.Cu" "F.Mask" "F.Paste")
			(net "P3V3")
			(options
				(clearance outline)
				(anchor circle)
			)
			(primitives
				(gr_poly
					(pts
						(arc
							(start -0.1778 -0.2794)
							(mid -0.249642 -0.249642)
							(end -0.2794 -0.1778)
						)
						(arc
							(start -0.2794 0.1778)
							(mid -0.249642 0.249642)
							(end -0.1778 0.2794)
						)
						(arc
							(start 0.1778 0.2794)
							(mid 0.249642 0.249642)
							(end 0.2794 0.1778)
						)
						(arc
							(start 0.2794 -0.1778)
							(mid 0.249642 -0.249642)
							(end 0.1778 -0.2794)
						)
					)
					(width 0)
					(fill yes)
				)
			)
		)
		(pad "2" smd custom
			(at 0 0.4445 90)
			(size 0.1397 0.1397)
			(layers "F.Cu" "F.Mask" "F.Paste")
			(net "PWM_OUT_FAN4")
			(options
				(clearance outline)
				(anchor circle)
			)
			(primitives
				(gr_poly
					(pts
						(arc
							(start -0.1778 -0.2794)
							(mid -0.249642 -0.249642)
							(end -0.2794 -0.1778)
						)
						(arc
							(start -0.2794 0.1778)
							(mid -0.249642 0.249642)
							(end -0.1778 0.2794)
						)
						(arc
							(start 0.1778 0.2794)
							(mid 0.249642 0.249642)
							(end 0.2794 0.1778)
						)
						(arc
							(start 0.2794 -0.1778)
							(mid 0.249642 -0.249642)
							(end 0.1778 -0.2794)
						)
					)
					(width 0)
					(fill yes)
				)
			)
		)
	)
	(footprint ""
		(layer "F.Cu")
		(at 30.3784 -210.8454 180)
		(property "Reference" "R139"
			(at 0 0 180)
			(layer "F.SilkS")
			(hide yes)
			(effects
				(font
					(size 1.27 1.27)
				)
			)
		)
		(property "Value" "0R2J-2-GP"
			(at 0.064008 -3.993896 180)
			(unlocked yes)
			(layer "F.Fab")
			(hide yes)
			(effects
				(font
					(size 1.016 1.016)
					(thickness 0.1524)
				)
			)
		)
		(property "Device Type" "R402H16"
			(at 0.064008 -5.517896 180)
			(unlocked yes)
			(layer "F.Fab")
			(hide yes)
			(effects
				(font
					(size 1.016 1.016)
					(thickness 0.1524)
				)
			)
		)
		(duplicate_pad_numbers_are_jumpers no)
		(fp_line
			(start 0.508 -0.9398)
			(end -0.508 -0.9398)
			(stroke
				(width 0.1524)
				(type default)
			)
			(layer "F.SilkS")
		)
		(fp_line
			(start -0.508 -0.9398)
			(end -0.508 0.9398)
			(stroke
				(width 0.1524)
				(type default)
			)
			(layer "F.SilkS")
		)
		(fp_rect
			(start -0.508 0.9398)
			(end 0.508 -0.9398)
			(stroke
				(width 0)
				(type default)
			)
			(fill no)
			(layer "F.CrtYd")
		)
		(fp_rect
			(start -0.508 0.9398)
			(end 0.508 -0.9398)
			(stroke
				(width 0)
				(type default)
			)
			(fill no)
			(layer "F.Fab")
		)
		(pad "1" smd custom
			(at 0 -0.4445 180)
			(size 0.1397 0.1397)
			(layers "F.Cu" "F.Mask" "F.Paste")
			(net "PWM_OUT_FAN4_NET")
			(options
				(clearance outline)
				(anchor circle)
			)
			(primitives
				(gr_poly
					(pts
						(arc
							(start -0.1778 -0.2794)
							(mid -0.249642 -0.249642)
							(end -0.2794 -0.1778)
						)
						(arc
							(start -0.2794 0.1778)
							(mid -0.249642 0.249642)
							(end -0.1778 0.2794)
						)
						(arc
							(start 0.1778 0.2794)
							(mid 0.249642 0.249642)
							(end 0.2794 0.1778)
						)
						(arc
							(start 0.2794 -0.1778)
							(mid 0.249642 -0.249642)
							(end 0.1778 -0.2794)
						)
					)
					(width 0)
					(fill yes)
				)
			)
		)
		(pad "2" smd custom
			(at 0 0.4445 180)
			(size 0.1397 0.1397)
			(layers "F.Cu" "F.Mask" "F.Paste")
			(net "PWM_OUT_FAN4")
			(options
				(clearance outline)
				(anchor circle)
			)
			(primitives
				(gr_poly
					(pts
						(arc
							(start -0.1778 -0.2794)
							(mid -0.249642 -0.249642)
							(end -0.2794 -0.1778)
						)
						(arc
							(start -0.2794 0.1778)
							(mid -0.249642 0.249642)
							(end -0.1778 0.2794)
						)
						(arc
							(start 0.1778 0.2794)
							(mid 0.249642 0.249642)
							(end 0.2794 0.1778)
						)
						(arc
							(start 0.2794 -0.1778)
							(mid 0.249642 -0.249642)
							(end 0.1778 -0.2794)
						)
					)
					(width 0)
					(fill yes)
				)
			)
		)
	)
	(footprint ""
		(layer "F.Cu")
		(at 28.2956 -361.0864 -90)
		(property "Reference" "PR16"
			(at 0 0 270)
			(layer "F.SilkS")
			(hide yes)
			(effects
				(font
					(size 1.27 1.27)
				)
			)
		)
		(property "Value" "1KR2F-3-GP"
			(at 0.064008 -3.993896 270)
			(unlocked yes)
			(layer "F.Fab")
			(hide yes)
			(effects
				(font
					(size 1.016 1.016)
					(thickness 0.1524)
				)
			)
		)
		(property "Device Type" "R402H16"
			(at 0.064008 -5.517896 270)
			(unlocked yes)
			(layer "F.Fab")
			(hide yes)
			(effects
				(font
					(size 1.016 1.016)
					(thickness 0.1524)
				)
			)
		)
		(duplicate_pad_numbers_are_jumpers no)
		(fp_line
			(start -0.508 -0.9398)
			(end -0.508 0.9398)
			(stroke
				(width 0.1524)
				(type default)
			)
			(layer "F.SilkS")
		)
		(fp_line
			(start 0.508 -0.9398)
			(end -0.508 -0.9398)
			(stroke
				(width 0.1524)
				(type default)
			)
			(layer "F.SilkS")
		)
		(fp_rect
			(start -0.508 0.9398)
			(end 0.508 -0.9398)
			(stroke
				(width 0)
				(type default)
			)
			(fill no)
			(layer "F.CrtYd")
		)
		(fp_rect
			(start -0.508 0.9398)
			(end 0.508 -0.9398)
			(stroke
				(width 0)
				(type default)
			)
			(fill no)
			(layer "F.Fab")
		)
		(pad "1" smd custom
			(at 0 -0.4445 270)
			(size 0.1397 0.1397)
			(layers "F.Cu" "F.Mask" "F.Paste")
			(net "ADM1276_EN")
			(options
				(clearance outline)
				(anchor circle)
			)
			(primitives
				(gr_poly
					(pts
						(arc
							(start -0.1778 -0.2794)
							(mid -0.249642 -0.249642)
							(end -0.2794 -0.1778)
						)
						(arc
							(start -0.2794 0.1778)
							(mid -0.249642 0.249642)
							(end -0.1778 0.2794)
						)
						(arc
							(start 0.1778 0.2794)
							(mid 0.249642 0.249642)
							(end 0.2794 0.1778)
						)
						(arc
							(start 0.2794 -0.1778)
							(mid 0.249642 -0.249642)
							(end 0.1778 -0.2794)
						)
					)
					(width 0)
					(fill yes)
				)
			)
		)
		(pad "2" smd custom
			(at 0 0.4445 270)
			(size 0.1397 0.1397)
			(layers "F.Cu" "F.Mask" "F.Paste")
			(net "GND")
			(options
				(clearance outline)
				(anchor circle)
			)
			(primitives
				(gr_poly
					(pts
						(arc
							(start -0.1778 -0.2794)
							(mid -0.249642 -0.249642)
							(end -0.2794 -0.1778)
						)
						(arc
							(start -0.2794 0.1778)
							(mid -0.249642 0.249642)
							(end -0.1778 0.2794)
						)
						(arc
							(start 0.1778 0.2794)
							(mid 0.249642 0.249642)
							(end 0.2794 0.1778)
						)
						(arc
							(start 0.2794 -0.1778)
							(mid 0.249642 -0.249642)
							(end 0.1778 -0.2794)
						)
					)
					(width 0)
					(fill yes)
				)
			)
		)
	)
	(footprint ""
		(layer "F.Cu")
		(at 27.7876 -150.7998 90)
		(property "Reference" "C7"
			(at 0 0 90)
			(layer "F.SilkS")
			(hide yes)
			(effects
				(font
					(size 1.27 1.27)
				)
			)
		)
		(property "Value" "SC2200P50V2KX-2GP"
			(at 1.1811 -2.7051 90)
			(unlocked yes)
			(layer "F.Fab")
			(hide yes)
			(effects
				(font
					(size 1.016 1.016)
					(thickness 0.1524)
				)
			)
		)
		(property "Device Type" "C402H22"
			(at 1.1811 -4.2291 90)
			(unlocked yes)
			(layer "F.Fab")
			(hide yes)
			(effects
				(font
					(size 1.016 1.016)
					(thickness 0.1524)
				)
			)
		)
		(duplicate_pad_numbers_are_jumpers no)
		(fp_rect
			(start -0.4318 0.9525)
			(end 0.4318 -0.9525)
			(stroke
				(width 0)
				(type default)
			)
			(fill no)
			(layer "F.CrtYd")
		)
		(fp_rect
			(start -0.4318 0.9525)
			(end 0.4318 -0.9525)
			(stroke
				(width 0)
				(type default)
			)
			(fill no)
			(layer "F.Fab")
		)
		(pad "1" smd custom
			(at 0 -0.4445 90)
			(size 0.1524 0.1524)
			(layers "F.Cu" "F.Mask" "F.Paste")
			(net "NCT7904_D1+")
			(options
				(clearance outline)
				(anchor circle)
			)
			(primitives
				(gr_poly
					(pts
						(arc
							(start 0.3048 -0.2032)
							(mid 0.275042 -0.275042)
							(end 0.2032 -0.3048)
						)
						(arc
							(start -0.2032 -0.3048)
							(mid -0.275042 -0.275042)
							(end -0.3048 -0.2032)
						)
						(arc
							(start -0.3048 0.2032)
							(mid -0.275042 0.275042)
							(end -0.2032 0.3048)
						)
						(arc
							(start 0.2032 0.3048)
							(mid 0.275042 0.275042)
							(end 0.3048 0.2032)
						)
					)
					(width 0)
					(fill yes)
				)
			)
		)
		(pad "2" smd custom
			(at 0 0.4445 90)
			(size 0.1524 0.1524)
			(layers "F.Cu" "F.Mask" "F.Paste")
			(net "NCT7904_D1-")
			(options
				(clearance outline)
				(anchor circle)
			)
			(primitives
				(gr_poly
					(pts
						(arc
							(start 0.3048 -0.2032)
							(mid 0.275042 -0.275042)
							(end 0.2032 -0.3048)
						)
						(arc
							(start -0.2032 -0.3048)
							(mid -0.275042 -0.275042)
							(end -0.3048 -0.2032)
						)
						(arc
							(start -0.3048 0.2032)
							(mid -0.275042 0.275042)
							(end -0.2032 0.3048)
						)
						(arc
							(start 0.2032 0.3048)
							(mid 0.275042 0.275042)
							(end 0.3048 0.2032)
						)
					)
					(width 0)
					(fill yes)
				)
			)
		)
	)
	(footprint ""
		(layer "F.Cu")
		(at 40.64 -410.591)
		(property "Reference" "PR32"
			(at 0 0 0)
			(layer "F.SilkS")
			(hide yes)
			(effects
				(font
					(size 1.27 1.27)
				)
			)
		)
		(property "Value" "D0005RL1632F-GP-U"
			(at 3.2258 1.2954 0)
			(unlocked yes)
			(layer "F.Fab")
			(hide yes)
			(effects
				(font
					(size 1.016 1.016)
					(thickness 0.1524)
				)
			)
		)
		(property "Device Type" "RL3115-4PH45"
			(at 3.2258 -0.2286 0)
			(unlocked yes)
			(layer "F.Fab")
			(hide yes)
			(effects
				(font
					(size 1.016 1.016)
					(thickness 0.1524)
				)
			)
		)
		(duplicate_pad_numbers_are_jumpers no)
		(fp_line
			(start -2.0574 -1.7653)
			(end -2.0574 -0.4064)
			(stroke
				(width 0.3302)
				(type default)
			)
			(layer "F.SilkS")
		)
		(fp_line
			(start -1.9685 -1.651)
			(end 1.9685 -1.651)
			(stroke
				(width 0.1524)
				(type default)
			)
			(layer "F.SilkS")
		)
		(fp_line
			(start -1.9685 1.651)
			(end -1.9685 -1.651)
			(stroke
				(width 0.1524)
				(type default)
			)
			(layer "F.SilkS")
		)
		(fp_line
			(start -0.5334 -1.7653)
			(end -2.0574 -1.7653)
			(stroke
				(width 0.3302)
				(type default)
			)
			(layer "F.SilkS")
		)
		(fp_line
			(start 1.9685 -1.651)
			(end 1.9685 1.651)
			(stroke
				(width 0.1524)
				(type default)
			)
			(layer "F.SilkS")
		)
		(fp_line
			(start 1.9685 1.651)
			(end -1.9685 1.651)
			(stroke
				(width 0.1524)
				(type default)
			)
			(layer "F.SilkS")
		)
		(fp_poly
			(pts
				(xy -0.561594 -1.726946) (xy -0.053594 -2.234946) (xy -1.069594 -2.234946)
			)
			(stroke
				(width 0)
				(type default)
			)
			(fill yes)
			(layer "F.SilkS")
		)
		(fp_rect
			(start -1.524 0.7493)
			(end 1.524 -0.7493)
			(stroke
				(width 0)
				(type default)
			)
			(fill no)
			(layer "F.CrtYd")
		)
		(fp_poly
			(pts
				(xy -2.2225 1.905) (xy -2.2225 -1.905) (xy 2.2225 -1.905) (xy 2.2225 -0.7493) (xy -1.524 -0.7493)
				(xy -1.524 0.7493) (xy 1.524 0.7493) (xy 1.524 -0.7366) (xy 2.2225 -0.7366) (xy 2.2225 1.905)
			)
			(stroke
				(width 0)
				(type default)
			)
			(fill no)
			(layer "F.CrtYd")
		)
		(fp_rect
			(start -2.2225 1.905)
			(end 2.2225 -1.905)
			(stroke
				(width 0)
				(type default)
			)
			(fill no)
			(layer "F.Fab")
		)
		(pad "1" smd rect
			(at -0.5715 -0.813562)
			(size 2.286 1.143)
			(layers "F.Cu" "F.Mask" "F.Paste")
			(net "P12V_AUX")
		)
		(pad "2" smd rect
			(at -0.5715 0.813562)
			(size 2.286 1.143)
			(layers "F.Cu" "F.Mask" "F.Paste")
			(net "P12V_SENSE_TRACE")
		)
		(pad "3" smd rect
			(at 1.334008 -0.813562)
			(size 0.762 1.143)
			(layers "F.Cu" "F.Mask" "F.Paste")
			(net "SENSE+_R4")
		)
		(pad "4" smd rect
			(at 1.334008 0.813562)
			(size 0.762 1.143)
			(layers "F.Cu" "F.Mask" "F.Paste")
			(net "SENSE-_R4")
		)
		(zone
			(layer "F.Cu")
			(hatch none 0.5)
			(connect_pads
				(clearance 0)
			)
			(min_thickness 0.25)
			(keepout
				(tracks not_allowed)
				(vias allowed)
				(pads allowed)
				(copperpour not_allowed)
				(footprints allowed)
			)
			(placement
				(enabled no)
				(sheetname "")
			)
			(fill
				(thermal_gap 0.5)
				(thermal_bridge_width 0.5)
				(island_removal_mode 0)
			)
			(polygon
				(pts
					(xy 41.2115 -410.833062) (xy 41.593008 -410.833062) (xy 41.593008 -411.3403) (xy 41.2115 -411.3403)
				)
			)
		)
		(zone
			(layer "F.Cu")
			(hatch none 0.5)
			(connect_pads
				(clearance 0)
			)
			(min_thickness 0.25)
			(keepout
				(tracks allowed)
				(vias not_allowed)
				(pads allowed)
				(copperpour not_allowed)
				(footprints allowed)
			)
			(placement
				(enabled no)
				(sheetname "")
			)
			(fill
				(thermal_gap 0.5)
				(thermal_bridge_width 0.5)
				(island_removal_mode 0)
			)
			(polygon
				(pts
					(xy 41.2115 -410.833062) (xy 41.593008 -410.833062) (xy 41.593008 -411.3403) (xy 41.2115 -411.3403)
				)
			)
		)
		(zone
			(layer "F.Cu")
			(hatch none 0.5)
			(connect_pads
				(clearance 0)
			)
			(min_thickness 0.25)
			(keepout
				(tracks allowed)
				(vias not_allowed)
				(pads allowed)
				(copperpour not_allowed)
				(footprints allowed)
			)
			(placement
				(enabled no)
				(sheetname "")
			)
			(fill
				(thermal_gap 0.5)
				(thermal_bridge_width 0.5)
				(island_removal_mode 0)
			)
			(polygon
				(pts
					(xy 41.2115 -409.8417) (xy 41.593008 -409.8417) (xy 41.593008 -410.348938) (xy 41.2115 -410.348938)
				)
			)
		)
		(zone
			(layer "F.Cu")
			(hatch none 0.5)
			(connect_pads
				(clearance 0)
			)
			(min_thickness 0.25)
			(keepout
				(tracks not_allowed)
				(vias allowed)
				(pads allowed)
				(copperpour not_allowed)
				(footprints allowed)
			)
			(placement
				(enabled no)
				(sheetname "")
			)
			(fill
				(thermal_gap 0.5)
				(thermal_bridge_width 0.5)
				(island_removal_mode 0)
			)
			(polygon
				(pts
					(xy 41.2115 -409.8417) (xy 41.593008 -409.8417) (xy 41.593008 -410.348938) (xy 41.2115 -410.348938)
				)
			)
		)
	)
	(footprint ""
		(layer "F.Cu")
		(at 43.8912 -90.6018 90)
		(property "Reference" "TC6"
			(at 0 0 90)
			(layer "F.SilkS")
			(hide yes)
			(effects
				(font
					(size 1.27 1.27)
				)
			)
		)
		(property "Value" "ST68U16VDM-1-GP"
			(at 0 -9.6012 90)
			(unlocked yes)
			(layer "F.Fab")
			(hide yes)
			(effects
				(font
					(size 1.016 1.016)
					(thickness 0.1524)
				)
			)
		)
		(property "Device Type" "CT7343H79"
			(at 0 -11.1252 90)
			(unlocked yes)
			(layer "F.Fab")
			(hide yes)
			(effects
				(font
					(size 1.016 1.016)
					(thickness 0.1524)
				)
			)
		)
		(duplicate_pad_numbers_are_jumpers no)
		(fp_line
			(start 2.286 -4.8768)
			(end -2.286 -4.8768)
			(stroke
				(width 0.1524)
				(type default)
			)
			(layer "F.SilkS")
		)
		(fp_line
			(start -2.286 -4.8768)
			(end -2.286 -2.032)
			(stroke
				(width 0.1524)
				(type default)
			)
			(layer "F.SilkS")
		)
		(fp_line
			(start 2.1082 -4.699)
			(end -2.1082 -4.699)
			(stroke
				(width 0.508)
				(type default)
			)
			(layer "F.SilkS")
		)
		(fp_line
			(start 2.286 -2.032)
			(end 2.286 -4.8768)
			(stroke
				(width 0.1524)
				(type default)
			)
			(layer "F.SilkS")
		)
		(fp_line
			(start 2.286 2.032)
			(end 2.286 4.8768)
			(stroke
				(width 0.1524)
				(type default)
			)
			(layer "F.SilkS")
		)
		(fp_line
			(start 2.286 4.8768)
			(end -2.286 4.8768)
			(stroke
				(width 0.1524)
				(type default)
			)
			(layer "F.SilkS")
		)
		(fp_line
			(start -2.286 4.8768)
			(end -2.286 2.032)
			(stroke
				(width 0.1524)
				(type default)
			)
			(layer "F.SilkS")
		)
		(fp_rect
			(start -2.1463 3.6449)
			(end 2.1463 -3.6449)
			(stroke
				(width 0)
				(type default)
			)
			(fill no)
			(layer "F.CrtYd")
		)
		(fp_poly
			(pts
				(xy -2.54 4.953) (xy -2.54 4.2926) (xy -3.81 4.2926) (xy -3.81 -4.2926) (xy -2.54 -4.2926) (xy -2.54 -4.953)
				(xy 2.54 -4.953) (xy 2.54 -4.2926) (xy 3.81 -4.2926) (xy 3.81 -1.6256) (xy 2.1463 -1.6256) (xy 2.1463 -3.6449)
				(xy -2.1463 -3.6449) (xy -2.1463 3.6449) (xy 2.1463 3.6449) (xy 2.1463 -1.6129) (xy 3.81 -1.6129)
				(xy 3.81 4.2926) (xy 2.54 4.2926) (xy 2.54 4.953)
			)
			(stroke
				(width 0)
				(type default)
			)
			(fill no)
			(layer "F.CrtYd")
		)
		(fp_rect
			(start 2.54 4.2926)
			(end 3.81 -4.2926)
			(stroke
				(width 0)
				(type default)
			)
			(fill no)
			(layer "F.Fab")
		)
		(fp_rect
			(start -3.81 4.2926)
			(end -2.54 -4.2926)
			(stroke
				(width 0)
				(type default)
			)
			(fill no)
			(layer "F.Fab")
		)
		(fp_rect
			(start -2.54 4.953)
			(end 2.54 -4.953)
			(stroke
				(width 0)
				(type default)
			)
			(fill no)
			(layer "F.Fab")
		)
		(pad "1" smd rect
			(at 0 -3.1496 90)
			(size 2.413 2.286)
			(layers "F.Cu" "F.Mask" "F.Paste")
			(net "P12VL")
		)
		(pad "2" smd rect
			(at 0 3.1496 90)
			(size 2.413 2.286)
			(layers "F.Cu" "F.Mask" "F.Paste")
			(net "GND")
		)
		(zone
			(layer "F.Cu")
			(hatch none 0.5)
			(connect_pads
				(clearance 0)
			)
			(min_thickness 0.25)
			(keepout
				(tracks allowed)
				(vias not_allowed)
				(pads allowed)
				(copperpour not_allowed)
				(footprints allowed)
			)
			(placement
				(enabled no)
				(sheetname "")
			)
			(fill
				(thermal_gap 0.5)
				(thermal_bridge_width 0.5)
				(island_removal_mode 0)
			)
			(polygon
				(pts
					(xy 42.2021 -92.1131) (xy 39.2938 -92.1131) (xy 39.2938 -89.0905) (xy 42.1894 -89.0905) (xy 42.5196 -89.0905)
					(xy 42.5196 -92.1131)
				)
			)
		)
		(zone
			(layer "F.Cu")
			(hatch none 0.5)
			(connect_pads
				(clearance 0)
			)
			(min_thickness 0.25)
			(keepout
				(tracks allowed)
				(vias not_allowed)
				(pads allowed)
				(copperpour not_allowed)
				(footprints allowed)
			)
			(placement
				(enabled no)
				(sheetname "")
			)
			(fill
				(thermal_gap 0.5)
				(thermal_bridge_width 0.5)
				(island_removal_mode 0)
			)
			(polygon
				(pts
					(xy 48.4886 -89.0905) (xy 48.4886 -92.1131) (xy 45.593 -92.1131) (xy 45.2628 -92.1131) (xy 45.2628 -89.0905)
					(xy 45.593 -89.0905)
				)
			)
		)
	)
)
